# T6G (Grand Teton) — schematic netlist excerpt (pin names and nets, part order shuffled) for the footprints in the layout excerpt that follows; sources: Cadence DE-HDL packaged netlist, KiCad conversion of 04192023_DAF0TMB3IC0_F0TG_MB_C_brd_V02_OCP.brd

C6035  Q_CAP  0.01UF 50V 10% X7R  pkg C0402  page 177 : A = P1V2_CPU0_USB_DVDD12 ; B = GND
C2454  Q_CAP  22UF 4V 20% X6S  pkg C0402  page 74 : A = PVDDCR_SOC_P1 ; B = GND

(kicad_pcb
	(version 20260206)
	(generator "pcbnew")
	(generator_version "10.0")
	(general
		(thickness 1.6)
		(legacy_teardrops no)
	)
	(paper "A4")
	(title_block
		(title "04192023_DAF0TMB3IC0_F0TG_MB_C_brd_V02_OCP.brd")
		(comment 1 "Grand Teton / footprints 8027-8028 of 8354")
	)
	(layers
		(0 "F.Cu" signal "TOP")
		(4 "In1.Cu" signal "GND")
		(6 "In2.Cu" signal "IN1")
		(8 "In3.Cu" signal "GND1")
		(10 "In4.Cu" signal "IN2")
		(12 "In5.Cu" signal "GND2")
		(14 "In6.Cu" signal "IN3")
		(16 "In7.Cu" signal "GND3")
		(18 "In8.Cu" signal "VCC")
		(20 "In9.Cu" signal "VCC1")
		(22 "In10.Cu" signal "GND4")
		(24 "In11.Cu" signal "IN4")
		(26 "In12.Cu" signal "GND5")
		(28 "In13.Cu" signal "IN5")
		(30 "In14.Cu" signal "GND6")
		(32 "In15.Cu" signal "IN6")
		(34 "In16.Cu" signal "GND7")
		(2 "B.Cu" signal "BOTTOM")
		(9 "F.Adhes" user "F.Adhesive")
		(11 "B.Adhes" user "B.Adhesive")
		(13 "F.Paste" user "Package Geometry/Pastemask Top")
		(15 "B.Paste" user "Package Geometry/Pastemask Bottom")
		(5 "F.SilkS" user "Ref Des/Silkscreen Top")
		(7 "B.SilkS" user "Ref Des/Silkscreen Bottom")
		(1 "F.Mask" user "Board Geometry/Soldermask Top")
		(3 "B.Mask" user "Board Geometry/Soldermask Bottom")
		(17 "Dwgs.User" user "User.Drawings")
		(19 "Cmts.User" user "User.Comments")
		(21 "Eco1.User" user "User.Eco1")
		(23 "Eco2.User" user "User.Eco2")
		(25 "Edge.Cuts" user "Board Geometry/Outline")
		(27 "Margin" user)
		(31 "F.CrtYd" user "Package Geometry/Place Bound Top")
		(29 "B.CrtYd" user "Package Geometry/Place Bound Bottom")
		(35 "F.Fab" user "Ref Des/Assembly Top")
		(33 "B.Fab" user "Ref Des/Assembly Bottom")
	)
	(footprint ""
		(layer "B.Cu")
		(at 123.611386 -254.194564)
		(property "Reference" "C2454"
			(at 0 0 0)
			(layer "B.SilkS")
			(hide yes)
			(effects
				(font
					(size 1.27 1.27)
				)
				(justify mirror)
			)
		)
		(property "Value" ""
			(at 0 0 0)
			(layer "B.Fab")
			(effects
				(font
					(size 1.27 1.27)
				)
				(justify mirror)
			)
		)
		(duplicate_pad_numbers_are_jumpers no)
		(fp_line
			(start -0.7874 -0.4064)
			(end -0.7874 0.4064)
			(stroke
				(width 0.1524)
				(type default)
			)
			(layer "B.SilkS")
		)
		(fp_line
			(start -0.7874 0.4064)
			(end 0.7874 0.4064)
			(stroke
				(width 0.1524)
				(type default)
			)
			(layer "B.SilkS")
		)
		(fp_line
			(start 0.7874 -0.4064)
			(end -0.7874 -0.4064)
			(stroke
				(width 0.1524)
				(type default)
			)
			(layer "B.SilkS")
		)
		(fp_line
			(start 0.7874 0.4064)
			(end 0.7874 -0.4064)
			(stroke
				(width 0.1524)
				(type default)
			)
			(layer "B.SilkS")
		)
		(fp_line
			(start -0.67945 -0.3048)
			(end -0.67945 0.3048)
			(stroke
				(width 0.1)
				(type default)
			)
			(layer "B.Fab")
		)
		(fp_line
			(start -0.67945 0.3048)
			(end -0.120396 0.3048)
			(stroke
				(width 0.1)
				(type default)
			)
			(layer "B.Fab")
		)
		(fp_line
			(start -0.12065 -0.3048)
			(end -0.67945 -0.3048)
			(stroke
				(width 0.1)
				(type default)
			)
			(layer "B.Fab")
		)
		(fp_line
			(start -0.12065 -0.2794)
			(end -0.12065 -0.3048)
			(stroke
				(width 0.1)
				(type default)
			)
			(layer "B.Fab")
		)
		(fp_line
			(start -0.120396 0.2794)
			(end 0.12065 0.2794)
			(stroke
				(width 0.1)
				(type default)
			)
			(layer "B.Fab")
		)
		(fp_line
			(start -0.120396 0.3048)
			(end -0.120396 0.2794)
			(stroke
				(width 0.1)
				(type default)
			)
			(layer "B.Fab")
		)
		(fp_line
			(start 0.12065 -0.305054)
			(end 0.12065 -0.2794)
			(stroke
				(width 0.1)
				(type default)
			)
			(layer "B.Fab")
		)
		(fp_line
			(start 0.12065 -0.2794)
			(end -0.12065 -0.2794)
			(stroke
				(width 0.1)
				(type default)
			)
			(layer "B.Fab")
		)
		(fp_line
			(start 0.12065 0.2794)
			(end 0.12065 0.3048)
			(stroke
				(width 0.1)
				(type default)
			)
			(layer "B.Fab")
		)
		(fp_line
			(start 0.12065 0.3048)
			(end 0.67945 0.3048)
			(stroke
				(width 0.1)
				(type default)
			)
			(layer "B.Fab")
		)
		(fp_line
			(start 0.67945 -0.305054)
			(end 0.12065 -0.305054)
			(stroke
				(width 0.1)
				(type default)
			)
			(layer "B.Fab")
		)
		(fp_line
			(start 0.67945 0.3048)
			(end 0.67945 -0.305054)
			(stroke
				(width 0.1)
				(type default)
			)
			(layer "B.Fab")
		)
		(pad "1" smd circle
			(at 0.40005 0 180)
			(size 0 0)
			(layers "B.Cu" "B.Mask" "B.Paste")
			(net "PVDDCR_SOC_P1")
		)
		(pad "2" smd circle
			(at -0.40005 0 180)
			(size 0 0)
			(layers "B.Cu" "B.Mask" "B.Paste")
			(net "GND")
		)
	)
	(footprint ""
		(layer "B.Cu")
		(at 134.840218 -40.111426)
		(property "Reference" "C6035"
			(at 0 0 0)
			(layer "B.SilkS")
			(hide yes)
			(effects
				(font
					(size 1.27 1.27)
				)
				(justify mirror)
			)
		)
		(property "Value" ""
			(at 0 0 0)
			(layer "B.Fab")
			(effects
				(font
					(size 1.27 1.27)
				)
				(justify mirror)
			)
		)
		(duplicate_pad_numbers_are_jumpers no)
		(fp_line
			(start -0.7874 -0.4064)
			(end -0.7874 0.4064)
			(stroke
				(width 0.1524)
				(type default)
			)
			(layer "B.SilkS")
		)
		(fp_line
			(start -0.7874 0.4064)
			(end 0.7874 0.4064)
			(stroke
				(width 0.1524)
				(type default)
			)
			(layer "B.SilkS")
		)
		(fp_line
			(start 0.7874 -0.4064)
			(end -0.7874 -0.4064)
			(stroke
				(width 0.1524)
				(type default)
			)
			(layer "B.SilkS")
		)
		(fp_line
			(start 0.7874 0.4064)
			(end 0.7874 -0.4064)
			(stroke
				(width 0.1524)
				(type default)
			)
			(layer "B.SilkS")
		)
		(fp_line
			(start -0.67945 -0.3048)
			(end -0.67945 0.3048)
			(stroke
				(width 0.1)
				(type default)
			)
			(layer "B.Fab")
		)
		(fp_line
			(start -0.67945 0.3048)
			(end -0.120396 0.3048)
			(stroke
				(width 0.1)
				(type default)
			)
			(layer "B.Fab")
		)
		(fp_line
			(start -0.12065 -0.3048)
			(end -0.67945 -0.3048)
			(stroke
				(width 0.1)
				(type default)
			)
			(layer "B.Fab")
		)
		(fp_line
			(start -0.12065 -0.2794)
			(end -0.12065 -0.3048)
			(stroke
				(width 0.1)
				(type default)
			)
			(layer "B.Fab")
		)
		(fp_line
			(start -0.120396 0.2794)
			(end 0.12065 0.2794)
			(stroke
				(width 0.1)
				(type default)
			)
			(layer "B.Fab")
		)
		(fp_line
			(start -0.120396 0.3048)
			(end -0.120396 0.2794)
			(stroke
				(width 0.1)
				(type default)
			)
			(layer "B.Fab")
		)
		(fp_line
			(start 0.12065 -0.305054)
			(end 0.12065 -0.2794)
			(stroke
				(width 0.1)
				(type default)
			)
			(layer "B.Fab")
		)
		(fp_line
			(start 0.12065 -0.2794)
			(end -0.12065 -0.2794)
			(stroke
				(width 0.1)
				(type default)
			)
			(layer "B.Fab")
		)
		(fp_line
			(start 0.12065 0.2794)
			(end 0.12065 0.3048)
			(stroke
				(width 0.1)
				(type default)
			)
			(layer "B.Fab")
		)
		(fp_line
			(start 0.12065 0.3048)
			(end 0.67945 0.3048)
			(stroke
				(width 0.1)
				(type default)
			)
			(layer "B.Fab")
		)
		(fp_line
			(start 0.67945 -0.305054)
			(end 0.12065 -0.305054)
			(stroke
				(width 0.1)
				(type default)
			)
			(layer "B.Fab")
		)
		(fp_line
			(start 0.67945 0.3048)
			(end 0.67945 -0.305054)
			(stroke
				(width 0.1)
				(type default)
			)
			(layer "B.Fab")
		)
		(pad "1" smd circle
			(at 0.40005 0 180)
			(size 0 0)
			(layers "B.Cu" "B.Mask" "B.Paste")
			(net "P1V2_CPU0_USB_DVDD12")
		)
		(pad "2" smd circle
			(at -0.40005 0 180)
			(size 0 0)
			(layers "B.Cu" "B.Mask" "B.Paste")
			(net "GND")
		)
	)
)
